(kicad_pcb
	(version 20260206)
	(generator "pcbnew")
	(generator_version "10.0")
	(general
		(thickness 1.6)
		(legacy_teardrops no)
	)
	(paper "A4")
	(title_block
		(title "04192023_DAF0TMB3IC0_F0TG_MB_C_brd_V02_OCP.brd")
		(comment 1 "Grand Teton / footprints 7185-7192 of 8354")
	)
	(layers
		(0 "F.Cu" signal "TOP")
		(4 "In1.Cu" signal "GND")
		(6 "In2.Cu" signal "IN1")
		(8 "In3.Cu" signal "GND1")
		(10 "In4.Cu" signal "IN2")
		(12 "In5.Cu" signal "GND2")
		(14 "In6.Cu" signal "IN3")
		(16 "In7.Cu" signal "GND3")
		(18 "In8.Cu" signal "VCC")
		(20 "In9.Cu" signal "VCC1")
		(22 "In10.Cu" signal "GND4")
		(24 "In11.Cu" signal "IN4")
		(26 "In12.Cu" signal "GND5")
		(28 "In13.Cu" signal "IN5")
		(30 "In14.Cu" signal "GND6")
		(32 "In15.Cu" signal "IN6")
		(34 "In16.Cu" signal "GND7")
		(2 "B.Cu" signal "BOTTOM")
		(9 "F.Adhes" user "F.Adhesive")
		(11 "B.Adhes" user "B.Adhesive")
		(13 "F.Paste" user "Package Geometry/Pastemask Top")
		(15 "B.Paste" user "Package Geometry/Pastemask Bottom")
		(5 "F.SilkS" user "Ref Des/Silkscreen Top")
		(7 "B.SilkS" user "Ref Des/Silkscreen Bottom")
		(1 "F.Mask" user "Board Geometry/Soldermask Top")
		(3 "B.Mask" user "Board Geometry/Soldermask Bottom")
		(17 "Dwgs.User" user "User.Drawings")
		(19 "Cmts.User" user "User.Comments")
		(21 "Eco1.User" user "User.Eco1")
		(23 "Eco2.User" user "User.Eco2")
		(25 "Edge.Cuts" user "Board Geometry/Outline")
		(27 "Margin" user)
		(31 "F.CrtYd" user "Package Geometry/Place Bound Top")
		(29 "B.CrtYd" user "Package Geometry/Place Bound Bottom")
		(35 "F.Fab" user "Ref Des/Assembly Top")
		(33 "B.Fab" user "Ref Des/Assembly Bottom")
	)
	(footprint ""
		(layer "B.Cu")
		(at 363.931454 -250.89231)
		(property "Reference" "C4179"
			(at 0 0 0)
			(layer "B.SilkS")
			(hide yes)
			(effects
				(font
					(size 1.27 1.27)
				)
				(justify mirror)
			)
		)
		(property "Value" ""
			(at 0 0 0)
			(layer "B.Fab")
			(effects
				(font
					(size 1.27 1.27)
				)
				(justify mirror)
			)
		)
		(duplicate_pad_numbers_are_jumpers no)
		(fp_line
			(start -0.7874 -0.4064)
			(end -0.7874 0.4064)
			(stroke
				(width 0.1524)
				(type default)
			)
			(layer "B.SilkS")
		)
		(fp_line
			(start -0.7874 0.4064)
			(end 0.7874 0.4064)
			(stroke
				(width 0.1524)
				(type default)
			)
			(layer "B.SilkS")
		)
		(fp_line
			(start 0.7874 -0.4064)
			(end -0.7874 -0.4064)
			(stroke
				(width 0.1524)
				(type default)
			)
			(layer "B.SilkS")
		)
		(fp_line
			(start 0.7874 0.4064)
			(end 0.7874 -0.4064)
			(stroke
				(width 0.1524)
				(type default)
			)
			(layer "B.SilkS")
		)
		(fp_line
			(start -0.67945 -0.3048)
			(end -0.67945 0.3048)
			(stroke
				(width 0.1)
				(type default)
			)
			(layer "B.Fab")
		)
		(fp_line
			(start -0.67945 0.3048)
			(end -0.120396 0.3048)
			(stroke
				(width 0.1)
				(type default)
			)
			(layer "B.Fab")
		)
		(fp_line
			(start -0.12065 -0.3048)
			(end -0.67945 -0.3048)
			(stroke
				(width 0.1)
				(type default)
			)
			(layer "B.Fab")
		)
		(fp_line
			(start -0.12065 -0.2794)
			(end -0.12065 -0.3048)
			(stroke
				(width 0.1)
				(type default)
			)
			(layer "B.Fab")
		)
		(fp_line
			(start -0.120396 0.2794)
			(end 0.12065 0.2794)
			(stroke
				(width 0.1)
				(type default)
			)
			(layer "B.Fab")
		)
		(fp_line
			(start -0.120396 0.3048)
			(end -0.120396 0.2794)
			(stroke
				(width 0.1)
				(type default)
			)
			(layer "B.Fab")
		)
		(fp_line
			(start 0.12065 -0.305054)
			(end 0.12065 -0.2794)
			(stroke
				(width 0.1)
				(type default)
			)
			(layer "B.Fab")
		)
		(fp_line
			(start 0.12065 -0.2794)
			(end -0.12065 -0.2794)
			(stroke
				(width 0.1)
				(type default)
			)
			(layer "B.Fab")
		)
		(fp_line
			(start 0.12065 0.2794)
			(end 0.12065 0.3048)
			(stroke
				(width 0.1)
				(type default)
			)
			(layer "B.Fab")
		)
		(fp_line
			(start 0.12065 0.3048)
			(end 0.67945 0.3048)
			(stroke
				(width 0.1)
				(type default)
			)
			(layer "B.Fab")
		)
		(fp_line
			(start 0.67945 -0.305054)
			(end 0.12065 -0.305054)
			(stroke
				(width 0.1)
				(type default)
			)
			(layer "B.Fab")
		)
		(fp_line
			(start 0.67945 0.3048)
			(end 0.67945 -0.305054)
			(stroke
				(width 0.1)
				(type default)
			)
			(layer "B.Fab")
		)
		(pad "1" smd circle
			(at 0.40005 0 180)
			(size 0 0)
			(layers "B.Cu" "B.Mask" "B.Paste")
			(net "PVDDCR_CPU0_P0")
		)
		(pad "2" smd circle
			(at -0.40005 0 180)
			(size 0 0)
			(layers "B.Cu" "B.Mask" "B.Paste")
			(net "GND")
		)
	)
	(footprint ""
		(layer "B.Cu")
		(at 398.880076 -169.49547 -90)
		(property "Reference" "PC8009"
			(at 0 0 90)
			(layer "B.SilkS")
			(hide yes)
			(effects
				(font
					(size 1.27 1.27)
				)
				(justify mirror)
			)
		)
		(property "Value" ""
			(at 0 0 90)
			(layer "B.Fab")
			(effects
				(font
					(size 1.27 1.27)
				)
				(justify mirror)
			)
		)
		(duplicate_pad_numbers_are_jumpers no)
		(fp_line
			(start -1.524 0.762)
			(end 1.524 0.762)
			(stroke
				(width 0.1524)
				(type default)
			)
			(layer "B.SilkS")
		)
		(fp_line
			(start 1.524 0.762)
			(end 1.524 -0.762)
			(stroke
				(width 0.1524)
				(type default)
			)
			(layer "B.SilkS")
		)
		(fp_line
			(start -1.524 -0.762)
			(end -1.524 0.762)
			(stroke
				(width 0.1524)
				(type default)
			)
			(layer "B.SilkS")
		)
		(fp_line
			(start 1.524 -0.762)
			(end -1.524 -0.762)
			(stroke
				(width 0.1524)
				(type default)
			)
			(layer "B.SilkS")
		)
		(fp_line
			(start -1.1049 0.724916)
			(end -1.1049 -0.724916)
			(stroke
				(width 0.1)
				(type default)
			)
			(layer "B.Fab")
		)
		(fp_line
			(start 1.1049 0.724916)
			(end -1.1049 0.724916)
			(stroke
				(width 0.1)
				(type default)
			)
			(layer "B.Fab")
		)
		(fp_line
			(start -1.1049 -0.724916)
			(end 1.1049 -0.724916)
			(stroke
				(width 0.1)
				(type default)
			)
			(layer "B.Fab")
		)
		(fp_line
			(start 1.1049 -0.724916)
			(end 1.1049 0.724916)
			(stroke
				(width 0.1)
				(type default)
			)
			(layer "B.Fab")
		)
		(pad "1" smd rect
			(at 0.889 0 270)
			(size 1.016 1.27)
			(layers "B.Cu" "B.Mask" "B.Paste")
			(net "SW_P12V_AUX_PVDDCR_SOC_P0_FLT")
		)
		(pad "2" smd rect
			(at -0.889 0 270)
			(size 1.016 1.27)
			(layers "B.Cu" "B.Mask" "B.Paste")
			(net "GND")
		)
	)
	(footprint ""
		(layer "B.Cu")
		(at 306.991004 -398.942052 90)
		(property "Reference" "C579"
			(at 0 0 90)
			(layer "B.SilkS")
			(hide yes)
			(effects
				(font
					(size 1.27 1.27)
				)
				(justify mirror)
			)
		)
		(property "Value" ""
			(at 0 0 90)
			(layer "B.Fab")
			(effects
				(font
					(size 1.27 1.27)
				)
				(justify mirror)
			)
		)
		(duplicate_pad_numbers_are_jumpers no)
		(fp_line
			(start 0.7874 -0.4064)
			(end -0.7874 -0.4064)
			(stroke
				(width 0.1524)
				(type default)
			)
			(layer "B.SilkS")
		)
		(fp_line
			(start -0.7874 -0.4064)
			(end -0.7874 0.4064)
			(stroke
				(width 0.1524)
				(type default)
			)
			(layer "B.SilkS")
		)
		(fp_line
			(start 0.7874 0.4064)
			(end 0.7874 -0.4064)
			(stroke
				(width 0.1524)
				(type default)
			)
			(layer "B.SilkS")
		)
		(fp_line
			(start -0.7874 0.4064)
			(end 0.7874 0.4064)
			(stroke
				(width 0.1524)
				(type default)
			)
			(layer "B.SilkS")
		)
		(fp_line
			(start 0.67945 -0.305054)
			(end 0.12065 -0.305054)
			(stroke
				(width 0.1)
				(type default)
			)
			(layer "B.Fab")
		)
		(fp_line
			(start 0.12065 -0.305054)
			(end 0.12065 -0.2794)
			(stroke
				(width 0.1)
				(type default)
			)
			(layer "B.Fab")
		)
		(fp_line
			(start -0.12065 -0.3048)
			(end -0.67945 -0.3048)
			(stroke
				(width 0.1)
				(type default)
			)
			(layer "B.Fab")
		)
		(fp_line
			(start -0.67945 -0.3048)
			(end -0.67945 0.3048)
			(stroke
				(width 0.1)
				(type default)
			)
			(layer "B.Fab")
		)
		(fp_line
			(start 0.12065 -0.2794)
			(end -0.12065 -0.2794)
			(stroke
				(width 0.1)
				(type default)
			)
			(layer "B.Fab")
		)
		(fp_line
			(start -0.12065 -0.2794)
			(end -0.12065 -0.3048)
			(stroke
				(width 0.1)
				(type default)
			)
			(layer "B.Fab")
		)
		(fp_line
			(start 0.12065 0.2794)
			(end 0.12065 0.3048)
			(stroke
				(width 0.1)
				(type default)
			)
			(layer "B.Fab")
		)
		(fp_line
			(start -0.120396 0.2794)
			(end 0.12065 0.2794)
			(stroke
				(width 0.1)
				(type default)
			)
			(layer "B.Fab")
		)
		(fp_line
			(start 0.67945 0.3048)
			(end 0.67945 -0.305054)
			(stroke
				(width 0.1)
				(type default)
			)
			(layer "B.Fab")
		)
		(fp_line
			(start 0.12065 0.3048)
			(end 0.67945 0.3048)
			(stroke
				(width 0.1)
				(type default)
			)
			(layer "B.Fab")
		)
		(fp_line
			(start -0.120396 0.3048)
			(end -0.120396 0.2794)
			(stroke
				(width 0.1)
				(type default)
			)
			(layer "B.Fab")
		)
		(fp_line
			(start -0.67945 0.3048)
			(end -0.120396 0.3048)
			(stroke
				(width 0.1)
				(type default)
			)
			(layer "B.Fab")
		)
		(pad "1" smd circle
			(at 0.40005 0 270)
			(size 0 0)
			(layers "B.Cu" "B.Mask" "B.Paste")
			(net "P0V9_CPU0_RT0_2A")
		)
		(pad "2" smd circle
			(at -0.40005 0 270)
			(size 0 0)
			(layers "B.Cu" "B.Mask" "B.Paste")
			(net "GND")
		)
	)
	(footprint ""
		(layer "B.Cu")
		(at 404.346156 -396.393162 -90)
		(property "Reference" "C800"
			(at 0 0 90)
			(layer "B.SilkS")
			(hide yes)
			(effects
				(font
					(size 1.27 1.27)
				)
				(justify mirror)
			)
		)
		(property "Value" ""
			(at 0 0 90)
			(layer "B.Fab")
			(effects
				(font
					(size 1.27 1.27)
				)
				(justify mirror)
			)
		)
		(duplicate_pad_numbers_are_jumpers no)
		(fp_line
			(start -0.299974 0.150114)
			(end 0.299974 0.150114)
			(stroke
				(width 0.1)
				(type default)
			)
			(layer "B.Fab")
		)
		(fp_line
			(start 0.299974 0.150114)
			(end 0.299974 -0.150114)
			(stroke
				(width 0.1)
				(type default)
			)
			(layer "B.Fab")
		)
		(fp_line
			(start -0.299974 -0.150114)
			(end -0.299974 0.150114)
			(stroke
				(width 0.1)
				(type default)
			)
			(layer "B.Fab")
		)
		(fp_line
			(start 0.299974 -0.150114)
			(end -0.299974 -0.150114)
			(stroke
				(width 0.1)
				(type default)
			)
			(layer "B.Fab")
		)
		(pad "1" smd rect
			(at 0.2667 0 90)
			(size 0.3048 0.381)
			(layers "B.Cu" "B.Mask" "B.Paste")
			(net "P0V9_CPU0_RT2_2A")
		)
		(pad "2" smd rect
			(at -0.2667 0 90)
			(size 0.3048 0.381)
			(layers "B.Cu" "B.Mask" "B.Paste")
			(net "GND")
		)
	)
	(footprint ""
		(layer "B.Cu")
		(at 347.906086 -395.148562 90)
		(property "Reference" "C619"
			(at 0 0 90)
			(layer "B.SilkS")
			(hide yes)
			(effects
				(font
					(size 1.27 1.27)
				)
				(justify mirror)
			)
		)
		(property "Value" ""
			(at 0 0 90)
			(layer "B.Fab")
			(effects
				(font
					(size 1.27 1.27)
				)
				(justify mirror)
			)
		)
		(duplicate_pad_numbers_are_jumpers no)
		(fp_line
			(start 0.299974 -0.150114)
			(end -0.299974 -0.150114)
			(stroke
				(width 0.1)
				(type default)
			)
			(layer "B.Fab")
		)
		(fp_line
			(start -0.299974 -0.150114)
			(end -0.299974 0.150114)
			(stroke
				(width 0.1)
				(type default)
			)
			(layer "B.Fab")
		)
		(fp_line
			(start 0.299974 0.150114)
			(end 0.299974 -0.150114)
			(stroke
				(width 0.1)
				(type default)
			)
			(layer "B.Fab")
		)
		(fp_line
			(start -0.299974 0.150114)
			(end 0.299974 0.150114)
			(stroke
				(width 0.1)
				(type default)
			)
			(layer "B.Fab")
		)
		(pad "1" smd rect
			(at 0.2667 0 270)
			(size 0.3048 0.381)
			(layers "B.Cu" "B.Mask" "B.Paste")
			(net "P0V9_CPU0_RT_2D")
		)
		(pad "2" smd rect
			(at -0.2667 0 270)
			(size 0.3048 0.381)
			(layers "B.Cu" "B.Mask" "B.Paste")
			(net "GND")
		)
	)
	(footprint ""
		(layer "B.Cu")
		(at 367.671858 -134.954772 180)
		(property "Reference" "R8282"
			(at 0 0 0)
			(layer "B.SilkS")
			(hide yes)
			(effects
				(font
					(size 1.27 1.27)
				)
				(justify mirror)
			)
		)
		(property "Value" ""
			(at 0 0 0)
			(layer "B.Fab")
			(effects
				(font
					(size 1.27 1.27)
				)
				(justify mirror)
			)
		)
		(duplicate_pad_numbers_are_jumpers no)
		(fp_line
			(start 0.7874 0.4064)
			(end 0.7874 -0.4064)
			(stroke
				(width 0.1524)
				(type default)
			)
			(layer "B.SilkS")
		)
		(fp_line
			(start 0.7874 -0.4064)
			(end -0.7874 -0.4064)
			(stroke
				(width 0.1524)
				(type default)
			)
			(layer "B.SilkS")
		)
		(fp_line
			(start -0.7874 0.4064)
			(end 0.7874 0.4064)
			(stroke
				(width 0.1524)
				(type default)
			)
			(layer "B.SilkS")
		)
		(fp_line
			(start -0.7874 -0.4064)
			(end -0.7874 0.4064)
			(stroke
				(width 0.1524)
				(type default)
			)
			(layer "B.SilkS")
		)
		(fp_line
			(start 0.67945 0.3048)
			(end 0.67945 -0.305054)
			(stroke
				(width 0.1)
				(type default)
			)
			(layer "B.Fab")
		)
		(fp_line
			(start 0.67945 -0.305054)
			(end 0.12065 -0.305054)
			(stroke
				(width 0.1)
				(type default)
			)
			(layer "B.Fab")
		)
		(fp_line
			(start 0.12065 0.3048)
			(end 0.67945 0.3048)
			(stroke
				(width 0.1)
				(type default)
			)
			(layer "B.Fab")
		)
		(fp_line
			(start 0.12065 0.2794)
			(end 0.12065 0.3048)
			(stroke
				(width 0.1)
				(type default)
			)
			(layer "B.Fab")
		)
		(fp_line
			(start 0.12065 -0.2794)
			(end -0.12065 -0.2794)
			(stroke
				(width 0.1)
				(type default)
			)
			(layer "B.Fab")
		)
		(fp_line
			(start 0.12065 -0.305054)
			(end 0.12065 -0.2794)
			(stroke
				(width 0.1)
				(type default)
			)
			(layer "B.Fab")
		)
		(fp_line
			(start -0.120396 0.3048)
			(end -0.120396 0.2794)
			(stroke
				(width 0.1)
				(type default)
			)
			(layer "B.Fab")
		)
		(fp_line
			(start -0.120396 0.2794)
			(end 0.12065 0.2794)
			(stroke
				(width 0.1)
				(type default)
			)
			(layer "B.Fab")
		)
		(fp_line
			(start -0.12065 -0.2794)
			(end -0.12065 -0.3048)
			(stroke
				(width 0.1)
				(type default)
			)
			(layer "B.Fab")
		)
		(fp_line
			(start -0.12065 -0.3048)
			(end -0.67945 -0.3048)
			(stroke
				(width 0.1)
				(type default)
			)
			(layer "B.Fab")
		)
		(fp_line
			(start -0.67945 0.3048)
			(end -0.120396 0.3048)
			(stroke
				(width 0.1)
				(type default)
			)
			(layer "B.Fab")
		)
		(fp_line
			(start -0.67945 -0.3048)
			(end -0.67945 0.3048)
			(stroke
				(width 0.1)
				(type default)
			)
			(layer "B.Fab")
		)
		(pad "1" smd circle
			(at 0.40005 0)
			(size 0 0)
			(layers "B.Cu" "B.Mask" "B.Paste")
			(net "PVDDCR_SOC_P0_EN")
		)
		(pad "2" smd circle
			(at -0.40005 0)
			(size 0 0)
			(layers "B.Cu" "B.Mask" "B.Paste")
			(net "PVDDCR_SOC_P0_EN_RC")
		)
	)
	(footprint ""
		(layer "B.Cu")
		(at 273.847814 -194.88531 180)
		(property "Reference" "R5"
			(at 0 0 0)
			(layer "B.SilkS")
			(hide yes)
			(effects
				(font
					(size 1.27 1.27)
				)
				(justify mirror)
			)
		)
		(property "Value" ""
			(at 0 0 0)
			(layer "B.Fab")
			(effects
				(font
					(size 1.27 1.27)
				)
				(justify mirror)
			)
		)
		(duplicate_pad_numbers_are_jumpers no)
		(fp_line
			(start 0.7874 0.4064)
			(end 0.7874 -0.4064)
			(stroke
				(width 0.1524)
				(type default)
			)
			(layer "B.SilkS")
		)
		(fp_line
			(start 0.7874 -0.4064)
			(end -0.7874 -0.4064)
			(stroke
				(width 0.1524)
				(type default)
			)
			(layer "B.SilkS")
		)
		(fp_line
			(start -0.7874 0.4064)
			(end 0.7874 0.4064)
			(stroke
				(width 0.1524)
				(type default)
			)
			(layer "B.SilkS")
		)
		(fp_line
			(start -0.7874 -0.4064)
			(end -0.7874 0.4064)
			(stroke
				(width 0.1524)
				(type default)
			)
			(layer "B.SilkS")
		)
		(fp_line
			(start 0.67945 0.3048)
			(end 0.67945 -0.305054)
			(stroke
				(width 0.1)
				(type default)
			)
			(layer "B.Fab")
		)
		(fp_line
			(start 0.67945 -0.305054)
			(end 0.12065 -0.305054)
			(stroke
				(width 0.1)
				(type default)
			)
			(layer "B.Fab")
		)
		(fp_line
			(start 0.12065 0.3048)
			(end 0.67945 0.3048)
			(stroke
				(width 0.1)
				(type default)
			)
			(layer "B.Fab")
		)
		(fp_line
			(start 0.12065 0.2794)
			(end 0.12065 0.3048)
			(stroke
				(width 0.1)
				(type default)
			)
			(layer "B.Fab")
		)
		(fp_line
			(start 0.12065 -0.2794)
			(end -0.12065 -0.2794)
			(stroke
				(width 0.1)
				(type default)
			)
			(layer "B.Fab")
		)
		(fp_line
			(start 0.12065 -0.305054)
			(end 0.12065 -0.2794)
			(stroke
				(width 0.1)
				(type default)
			)
			(layer "B.Fab")
		)
		(fp_line
			(start -0.120396 0.3048)
			(end -0.120396 0.2794)
			(stroke
				(width 0.1)
				(type default)
			)
			(layer "B.Fab")
		)
		(fp_line
			(start -0.120396 0.2794)
			(end 0.12065 0.2794)
			(stroke
				(width 0.1)
				(type default)
			)
			(layer "B.Fab")
		)
		(fp_line
			(start -0.12065 -0.2794)
			(end -0.12065 -0.3048)
			(stroke
				(width 0.1)
				(type default)
			)
			(layer "B.Fab")
		)
		(fp_line
			(start -0.12065 -0.3048)
			(end -0.67945 -0.3048)
			(stroke
				(width 0.1)
				(type default)
			)
			(layer "B.Fab")
		)
		(fp_line
			(start -0.67945 0.3048)
			(end -0.120396 0.3048)
			(stroke
				(width 0.1)
				(type default)
			)
			(layer "B.Fab")
		)
		(fp_line
			(start -0.67945 -0.3048)
			(end -0.67945 0.3048)
			(stroke
				(width 0.1)
				(type default)
			)
			(layer "B.Fab")
		)
		(pad "1" smd circle
			(at 0.40005 0)
			(size 0 0)
			(layers "B.Cu" "B.Mask" "B.Paste")
			(net "PD_CHE_CPU0_DIMM_SAA")
		)
		(pad "2" smd circle
			(at -0.40005 0)
			(size 0 0)
			(layers "B.Cu" "B.Mask" "B.Paste")
			(net "GND")
		)
	)
	(footprint ""
		(layer "B.Cu")
		(at 343.105994 -395.148562 90)
		(property "Reference" "C600"
			(at 0 0 90)
			(layer "B.SilkS")
			(hide yes)
			(effects
				(font
					(size 1.27 1.27)
				)
				(justify mirror)
			)
		)
		(property "Value" ""
			(at 0 0 90)
			(layer "B.Fab")
			(effects
				(font
					(size 1.27 1.27)
				)
				(justify mirror)
			)
		)
		(duplicate_pad_numbers_are_jumpers no)
		(fp_line
			(start 0.299974 -0.150114)
			(end -0.299974 -0.150114)
			(stroke
				(width 0.1)
				(type default)
			)
			(layer "B.Fab")
		)
		(fp_line
			(start -0.299974 -0.150114)
			(end -0.299974 0.150114)
			(stroke
				(width 0.1)
				(type default)
			)
			(layer "B.Fab")
		)
		(fp_line
			(start 0.299974 0.150114)
			(end 0.299974 -0.150114)
			(stroke
				(width 0.1)
				(type default)
			)
			(layer "B.Fab")
		)
		(fp_line
			(start -0.299974 0.150114)
			(end 0.299974 0.150114)
			(stroke
				(width 0.1)
				(type default)
			)
			(layer "B.Fab")
		)
		(pad "1" smd rect
			(at 0.2667 0 270)
			(size 0.3048 0.381)
			(layers "B.Cu" "B.Mask" "B.Paste")
			(net "P1V8_CPU0_RT1_1A")
		)
		(pad "2" smd rect
			(at -0.2667 0 270)
			(size 0.3048 0.381)
			(layers "B.Cu" "B.Mask" "B.Paste")
			(net "GND")
		)
	)
)
